(kicad_pcb
	(version 20241229)
	(generator "pcbnew")
	(generator_version "9.0")
	(general
		(thickness 1.61)
		(legacy_teardrops no)
	)
	(paper "A3")
	(title_block
		(title "SO-DIMM DDR5 Tester")
		(date "2025-11-26")
		(rev "1.3.0")
		(comment 9 "footprints 200-202 of 627")
	)
	(layers
		(0 "F.Cu" signal)
		(4 "In1.Cu" power)
		(6 "In2.Cu" mixed)
		(8 "In3.Cu" power)
		(10 "In4.Cu" mixed)
		(12 "In5.Cu" power)
		(14 "In6.Cu" mixed)
		(16 "In7.Cu" power)
		(18 "In8.Cu" power)
		(20 "In9.Cu" mixed)
		(22 "In10.Cu" power)
		(2 "B.Cu" signal)
		(9 "F.Adhes" user "F.Adhesive")
		(11 "B.Adhes" user "B.Adhesive")
		(13 "F.Paste" user)
		(15 "B.Paste" user)
		(5 "F.SilkS" user "F.Silkscreen")
		(7 "B.SilkS" user "B.Silkscreen")
		(1 "F.Mask" user)
		(3 "B.Mask" user)
		(17 "Dwgs.User" user "User.Drawings")
		(19 "Cmts.User" user "User.Comments")
		(21 "Eco1.User" user "User.Eco1")
		(23 "Eco2.User" user "User.Eco2")
		(25 "Edge.Cuts" user)
		(27 "Margin" user)
		(31 "F.CrtYd" user "F.Courtyard")
		(29 "B.CrtYd" user "B.Courtyard")
		(35 "F.Fab" user)
		(33 "B.Fab" user)
	)
	(footprint "antmicro-footprints:VQFN-16-1EP_3x3mm_P0.5mm_EP1.1x1.1mm"
		(layer "F.Cu")
		(at 182.387107 166.75 -90)
		(descr "VQFN, 16 Pin (https://ww1.microchip.com/downloads/en/DeviceDoc/16L_VQFN-WFS_3x3mm_4MX_C04-00508a.pdf), generated with kicad-footprint-generator ipc_noLead_generator.py")
		(tags "VQFN NoLead")
		(property "Reference" "U30"
			(at 3.35 -0.012893 0)
			(layer "F.SilkS")
			(effects
				(font
					(size 0.7 0.7)
					(thickness 0.15)
				)
				(justify left bottom)
			)
		)
		(property "Value" "PAC1954T-E_VQFN"
			(at 0 2.797 270)
			(layer "F.Fab")
			(effects
				(font
					(size 0.7 0.7)
					(thickness 0.15)
				)
				(justify left bottom)
			)
		)
		(property "Datasheet" "https://ww1.microchip.com/downloads/aemDocuments/documents/MSLD/ProductDocuments/DataSheets/PAC195X-Family-Data-Sheet-DS20006539.pdf"
			(at 0 0 270)
			(layer "F.Fab")
			(hide yes)
			(effects
				(font
					(size 1.27 1.27)
					(thickness 0.15)
				)
			)
		)
		(property "Author" "Antmicro"
			(at 15.637107 349.137107 0)
			(layer "F.Fab")
			(hide yes)
			(effects
				(font
					(size 1 1)
					(thickness 0.15)
				)
			)
		)
		(property "License" "Apache-2.0"
			(at 15.637107 349.137107 0)
			(layer "F.Fab")
			(hide yes)
			(effects
				(font
					(size 1 1)
					(thickness 0.15)
				)
			)
		)
		(property "MPN" "PAC1954T-E/4MX"
			(at 15.637107 349.137107 0)
			(layer "F.Fab")
			(hide yes)
			(effects
				(font
					(size 1 1)
					(thickness 0.15)
				)
			)
		)
		(property "Manufacturer" "Microchip Technology"
			(at 15.637107 349.137107 0)
			(layer "F.Fab")
			(hide yes)
			(effects
				(font
					(size 1 1)
					(thickness 0.15)
				)
			)
		)
		(property ki_fp_filters "UQFN*1EP*4x4mm*P0.65mm*")
		(sheetname "/Supply/")
		(sheetfile "supply.kicad_sch")
		(attr smd)
		(fp_line
			(start -1.611 1.61)
			(end -1.611 1.134)
			(stroke
				(width 0.15)
				(type solid)
			)
			(layer "F.SilkS")
		)
		(fp_line
			(start -1.135 1.61)
			(end -1.611 1.61)
			(stroke
				(width 0.15)
				(type solid)
			)
			(layer "F.SilkS")
		)
		(fp_line
			(start 1.134 1.61)
			(end 1.61 1.61)
			(stroke
				(width 0.15)
				(type solid)
			)
			(layer "F.SilkS")
		)
		(fp_line
			(start 1.61 1.61)
			(end 1.61 1.134)
			(stroke
				(width 0.15)
				(type solid)
			)
			(layer "F.SilkS")
		)
		(fp_line
			(start -1.135 -1.611)
			(end -1.611 -1.611)
			(stroke
				(width 0.15)
				(type solid)
			)
			(layer "F.SilkS")
		)
		(fp_line
			(start 1.134 -1.611)
			(end 1.61 -1.611)
			(stroke
				(width 0.15)
				(type solid)
			)
			(layer "F.SilkS")
		)
		(fp_line
			(start 1.61 -1.611)
			(end 1.61 -1.135)
			(stroke
				(width 0.15)
				(type solid)
			)
			(layer "F.SilkS")
		)
		(fp_circle
			(center -2.3 -0.75)
			(end -2.25 -0.75)
			(stroke
				(width 0.15)
				(type solid)
			)
			(fill yes)
			(layer "F.SilkS")
		)
		(fp_rect
			(start -2 -2)
			(end 1.999 1.999)
			(stroke
				(width 0.05)
				(type solid)
			)
			(fill no)
			(layer "F.CrtYd")
		)
		(fp_line
			(start -1.5 1.499)
			(end -1.5 -0.75)
			(stroke
				(width 0.15)
				(type solid)
			)
			(layer "F.Fab")
		)
		(fp_line
			(start 1.499 1.499)
			(end -1.5 1.499)
			(stroke
				(width 0.15)
				(type solid)
			)
			(layer "F.Fab")
		)
		(fp_line
			(start -1.5 -0.75)
			(end -0.75 -1.5)
			(stroke
				(width 0.15)
				(type solid)
			)
			(layer "F.Fab")
		)
		(fp_line
			(start -0.75 -1.5)
			(end 1.499 -1.5)
			(stroke
				(width 0.15)
				(type solid)
			)
			(layer "F.Fab")
		)
		(fp_line
			(start 1.499 -1.5)
			(end 1.499 1.499)
			(stroke
				(width 0.15)
				(type solid)
			)
			(layer "F.Fab")
		)
		(fp_circle
			(center -2.3 -0.75)
			(end -2.25 -0.75)
			(stroke
				(width 0.15)
				(type solid)
			)
			(fill yes)
			(layer "F.Fab")
		)
		(pad "" smd roundrect
			(at 0 0 270)
			(size 0.89 0.89)
			(layers "F.Paste")
			(roundrect_rratio 0.25)
		)
		(pad "1" smd roundrect
			(at -1.464 -0.75 270)
			(size 0.775 0.25)
			(layers "F.Cu" "F.Mask" "F.Paste")
			(roundrect_rratio 0.25)
			(net 1 "GND")
			(pinfunction "SLOW/~{ALERT1}")
			(pintype "bidirectional")
		)
		(pad "2" smd roundrect
			(at -1.464 -0.25 270)
			(size 0.775 0.25)
			(layers "F.Cu" "F.Mask" "F.Paste")
			(roundrect_rratio 0.25)
			(net 200 "+3V3")
			(pinfunction "VDD")
			(pintype "power_in")
		)
		(pad "3" smd roundrect
			(at -1.464 0.247 270)
			(size 0.775 0.25)
			(layers "F.Cu" "F.Mask" "F.Paste")
			(roundrect_rratio 0.25)
			(net 1 "GND")
			(pinfunction "GND")
			(pintype "power_in")
		)
		(pad "4" smd roundrect
			(at -1.464 0.747 270)
			(size 0.775 0.25)
			(layers "F.Cu" "F.Mask" "F.Paste")
			(roundrect_rratio 0.25)
			(net 297 "/Supply/PWR_SCL_2")
			(pinfunction "SCL")
			(pintype "input")
		)
		(pad "5" smd roundrect
			(at -0.75 1.461 270)
			(size 0.25 0.775)
			(layers "F.Cu" "F.Mask" "F.Paste")
			(roundrect_rratio 0.25)
			(net 298 "/Supply/PWR_SDA_2")
			(pinfunction "SDA")
			(pintype "bidirectional")
		)
		(pad "6" smd roundrect
			(at -0.25 1.461 270)
			(size 0.25 0.775)
			(layers "F.Cu" "F.Mask" "F.Paste")
			(roundrect_rratio 0.25)
			(net 1 "GND")
			(pinfunction "ADDRSEL")
			(pintype "bidirectional")
		)
		(pad "7" smd roundrect
			(at 0.247 1.461 270)
			(size 0.25 0.775)
			(layers "F.Cu" "F.Mask" "F.Paste")
			(roundrect_rratio 0.25)
			(net 175 "/Supply/1V1_SEN_-")
			(pinfunction "IN3-")
			(pintype "input")
		)
		(pad "8" smd roundrect
			(at 0.747 1.461 270)
			(size 0.25 0.775)
			(layers "F.Cu" "F.Mask" "F.Paste")
			(roundrect_rratio 0.25)
			(net 142 "/Supply/1V1_SEN_+")
			(pinfunction "IN3+")
			(pintype "input")
		)
		(pad "9" smd roundrect
			(at 1.461 0.747 270)
			(size 0.775 0.25)
			(layers "F.Cu" "F.Mask" "F.Paste")
			(roundrect_rratio 0.25)
			(net 144 "/Supply/1V2_SEN_-")
			(pinfunction "IN4-")
			(pintype "input")
		)
		(pad "10" smd roundrect
			(at 1.461 0.247 270)
			(size 0.775 0.25)
			(layers "F.Cu" "F.Mask" "F.Paste")
			(roundrect_rratio 0.25)
			(net 90 "/Supply/1V2_SEN_+")
			(pinfunction "IN4+")
			(pintype "input")
		)
		(pad "11" smd roundrect
			(at 1.461 -0.25 270)
			(size 0.775 0.25)
			(layers "F.Cu" "F.Mask" "F.Paste")
			(roundrect_rratio 0.25)
			(net 243 "/Supply/3V3_SEN_+")
			(pinfunction "IN1+")
			(pintype "input")
		)
		(pad "12" smd roundrect
			(at 1.461 -0.75 270)
			(size 0.775 0.25)
			(layers "F.Cu" "F.Mask" "F.Paste")
			(roundrect_rratio 0.25)
			(net 245 "/Supply/3V3_SEN_-")
			(pinfunction "IN1-")
			(pintype "input")
		)
		(pad "13" smd roundrect
			(at 0.747 -1.464 270)
			(size 0.25 0.775)
			(layers "F.Cu" "F.Mask" "F.Paste")
			(roundrect_rratio 0.25)
			(net 141 "/Supply/5V_SEN_+")
			(pinfunction "IN2+")
			(pintype "input")
		)
		(pad "14" smd roundrect
			(at 0.247 -1.464 270)
			(size 0.25 0.775)
			(layers "F.Cu" "F.Mask" "F.Paste")
			(roundrect_rratio 0.25)
			(net 146 "/Supply/5V_SEN_-")
			(pinfunction "IN2-")
			(pintype "input")
		)
		(pad "15" smd roundrect
			(at -0.25 -1.464 270)
			(size 0.25 0.775)
			(layers "F.Cu" "F.Mask" "F.Paste")
			(roundrect_rratio 0.25)
			(net 1 "GND")
			(pinfunction "GPIO/~{ALERT2}")
			(pintype "bidirectional")
		)
		(pad "16" smd roundrect
			(at -0.75 -1.464 270)
			(size 0.25 0.775)
			(layers "F.Cu" "F.Mask" "F.Paste")
			(roundrect_rratio 0.25)
			(net 386 "Net-(U30-~{PWRDN})")
			(pinfunction "~{PWRDN}")
			(pintype "input")
		)
		(pad "17" smd rect
			(at 0 0 270)
			(size 1.1 1.1)
			(layers "F.Cu" "F.Mask")
			(net 743 "unconnected-(U30-EP-Pad17)")
			(pinfunction "EP")
			(pintype "no_connect")
		)
	)
	(footprint "antmicro-footprints:C_0402_1005Metric"
		(layer "F.Cu")
		(at 183.541 148.650001)
		(descr "Capacitor SMD 0402")
		(tags "capacitor SMD 0402")
		(property "Reference" "C205"
			(at 0 -0.699 0)
			(layer "F.SilkS")
			(hide yes)
			(effects
				(font
					(size 0.7 0.7)
					(thickness 0.15)
				)
				(justify left bottom)
			)
		)
		(property "Value" "C_100n_0402"
			(at -1.022927 2.155213 0)
			(layer "F.Fab")
			(effects
				(font
					(size 0.7 0.7)
					(thickness 0.15)
				)
				(justify left bottom)
			)
		)
		(property "Datasheet" "https://www.murata.com/products/productdetail?partno=GRM155R61H104KE14%23"
			(at 0 0 0)
			(layer "F.Fab")
			(hide yes)
			(effects
				(font
					(size 1.27 1.27)
					(thickness 0.15)
				)
			)
		)
		(property "Author" "Antmicro"
			(at 0 0 0)
			(layer "F.Fab")
			(hide yes)
			(effects
				(font
					(size 1 1)
					(thickness 0.15)
				)
			)
		)
		(property "Dielectric" "X5R"
			(at 0 0 0)
			(layer "F.Fab")
			(hide yes)
			(effects
				(font
					(size 1 1)
					(thickness 0.15)
				)
			)
		)
		(property "License" "Apache-2.0"
			(at 0 0 0)
			(layer "F.Fab")
			(hide yes)
			(effects
				(font
					(size 1 1)
					(thickness 0.15)
				)
			)
		)
		(property "MPN" "GRM155R61H104KE14D"
			(at 0 0 0)
			(layer "F.Fab")
			(hide yes)
			(effects
				(font
					(size 1 1)
					(thickness 0.15)
				)
			)
		)
		(property "Manufacturer" "Murata"
			(at 0 0 0)
			(layer "F.Fab")
			(hide yes)
			(effects
				(font
					(size 1 1)
					(thickness 0.15)
				)
			)
		)
		(property "Val" "100n"
			(at 0 0 0)
			(layer "F.Fab")
			(hide yes)
			(effects
				(font
					(size 1 1)
					(thickness 0.15)
				)
			)
		)
		(property "Voltage" "50V"
			(at 0 0 0)
			(layer "F.Fab")
			(hide yes)
			(effects
				(font
					(size 1 1)
					(thickness 0.15)
				)
			)
		)
		(sheetname "/Supply/")
		(sheetfile "supply.kicad_sch")
		(attr smd)
		(fp_rect
			(start -0.9659 -0.481258)
			(end 0.9649 0.458742)
			(stroke
				(width 0.05)
				(type solid)
			)
			(fill no)
			(layer "F.CrtYd")
		)
		(fp_line
			(start -0.499 -0.25)
			(end 0.499 -0.25)
			(stroke
				(width 0.15)
				(type solid)
			)
			(layer "F.Fab")
		)
		(fp_line
			(start -0.499 0.248)
			(end -0.499 -0.25)
			(stroke
				(width 0.15)
				(type solid)
			)
			(layer "F.Fab")
		)
		(fp_line
			(start 0.499 -0.25)
			(end 0.499 0.248)
			(stroke
				(width 0.15)
				(type solid)
			)
			(layer "F.Fab")
		)
		(fp_line
			(start 0.499 0.248)
			(end -0.499 0.248)
			(stroke
				(width 0.15)
				(type solid)
			)
			(layer "F.Fab")
		)
		(pad "1" smd roundrect
			(at -0.484 0)
			(size 0.59 0.64)
			(layers "F.Cu" "F.Mask" "F.Paste")
			(roundrect_rratio 0.25)
			(net 1 "GND")
			(pintype "passive")
		)
		(pad "2" smd roundrect
			(at 0.484 0)
			(size 0.59 0.64)
			(layers "F.Cu" "F.Mask" "F.Paste")
			(roundrect_rratio 0.25)
			(net 200 "+3V3")
			(pintype "passive")
		)
	)
	(footprint "antmicro-footprints:X1QFN-16-1EP_2.5x2.5mm"
		(layer "F.Cu")
		(at 95.299 191.85)
		(property "Reference" "U9"
			(at 1.651 1.85 0)
			(unlocked yes)
			(layer "F.SilkS")
			(effects
				(font
					(size 0.7 0.7)
					(thickness 0.15)
				)
				(justify left bottom)
			)
		)
		(property "Value" "SN74HC595B"
			(at -6.9 2.69 0)
			(unlocked yes)
			(layer "F.Fab")
			(effects
				(font
					(size 0.7 0.7)
					(thickness 0.15)
				)
				(justify left bottom)
			)
		)
		(property "Datasheet" "https://www.ti.com/general/docs/suppproductinfo.tsp?distId=26&gotoUrl=https://www.ti.com/lit/gpn/sn74hc595b"
			(at 0 0 0)
			(layer "F.Fab")
			(hide yes)
			(effects
				(font
					(size 1.27 1.27)
					(thickness 0.15)
				)
			)
		)
		(property "Author" "Antmicro"
			(at 0 0 0)
			(layer "F.Fab")
			(hide yes)
			(effects
				(font
					(size 1 1)
					(thickness 0.15)
				)
			)
		)
		(property "License" "Apache-2.0"
			(at 0 0 0)
			(layer "F.Fab")
			(hide yes)
			(effects
				(font
					(size 1 1)
					(thickness 0.15)
				)
			)
		)
		(property "MPN" "SN74HC595BRWNR"
			(at 0 0 0)
			(layer "F.Fab")
			(hide yes)
			(effects
				(font
					(size 1 1)
					(thickness 0.15)
				)
			)
		)
		(property "Manufacturer" "Texas Instruments"
			(at 0 0 0)
			(layer "F.Fab")
			(hide yes)
			(effects
				(font
					(size 1 1)
					(thickness 0.15)
				)
			)
		)
		(sheetname "/Debug FTDI/")
		(sheetfile "debug-ftdi.kicad_sch")
		(attr smd)
		(fp_line
			(start -1.351 -1.351)
			(end -0.803 -1.351)
			(stroke
				(width 0.15)
				(type solid)
			)
			(layer "F.SilkS")
		)
		(fp_line
			(start -1.351 1.35)
			(end -1.351 0.8)
			(stroke
				(width 0.15)
				(type solid)
			)
			(layer "F.SilkS")
		)
		(fp_line
			(start -0.803 1.35)
			(end -1.351 1.35)
			(stroke
				(width 0.15)
				(type solid)
			)
			(layer "F.SilkS")
		)
		(fp_line
			(start 0.8 -1.351)
			(end 1.35 -1.351)
			(stroke
				(width 0.15)
				(type solid)
			)
			(layer "F.SilkS")
		)
		(fp_line
			(start 1.35 -1.351)
			(end 1.35 -0.803)
			(stroke
				(width 0.15)
				(type solid)
			)
			(layer "F.SilkS")
		)
		(fp_line
			(start 1.35 0.8)
			(end 1.35 1.35)
			(stroke
				(width 0.15)
				(type solid)
			)
			(layer "F.SilkS")
		)
		(fp_line
			(start 1.35 1.35)
			(end 0.8 1.35)
			(stroke
				(width 0.15)
				(type solid)
			)
			(layer "F.SilkS")
		)
		(fp_circle
			(center -1.752 -0.6)
			(end -1.702 -0.6)
			(stroke
				(width 0.15)
				(type solid)
			)
			(fill yes)
			(layer "F.SilkS")
		)
		(fp_rect
			(start -1.75 -1.75)
			(end 1.749 1.749)
			(stroke
				(width 0.05)
				(type solid)
			)
			(fill no)
			(layer "F.CrtYd")
		)
		(fp_line
			(start -1.25 -1.05)
			(end -1.05 -1.25)
			(stroke
				(width 0.15)
				(type solid)
			)
			(layer "F.Fab")
		)
		(fp_rect
			(start -1.25 -1.25)
			(end 1.249 1.249)
			(stroke
				(width 0.15)
				(type solid)
			)
			(fill no)
			(layer "F.Fab")
		)
		(pad "1" smd roundrect
			(at -1.151 -0.6)
			(size 0.6 0.2)
			(layers "F.Cu" "F.Mask" "F.Paste")
			(roundrect_rratio 0.25)
			(net 712 "unconnected-(U9-QB-Pad1)")
			(pinfunction "QB")
			(pintype "output+no_connect")
		)
		(pad "2" smd roundrect
			(at -1.151 -0.203)
			(size 0.6 0.2)
			(layers "F.Cu" "F.Mask" "F.Paste")
			(roundrect_rratio 0.25)
			(net 713 "unconnected-(U9-QC-Pad2)")
			(pinfunction "QC")
			(pintype "output+no_connect")
		)
		(pad "3" smd roundrect
			(at -1.151 0.2)
			(size 0.6 0.2)
			(layers "F.Cu" "F.Mask" "F.Paste")
			(roundrect_rratio 0.25)
			(net 714 "unconnected-(U9-QD-Pad3)")
			(pinfunction "QD")
			(pintype "output+no_connect")
		)
		(pad "4" smd roundrect
			(at -1.151 0.597)
			(size 0.6 0.2)
			(layers "F.Cu" "F.Mask" "F.Paste")
			(roundrect_rratio 0.25)
			(net 656 "/Debug FTDI/LED_TX0")
			(pinfunction "QE")
			(pintype "output")
		)
		(pad "5" smd roundrect
			(at -0.6 1.148 90)
			(size 0.6 0.2)
			(layers "F.Cu" "F.Mask" "F.Paste")
			(roundrect_rratio 0.25)
			(net 657 "/Debug FTDI/LED_RX0")
			(pinfunction "QF")
			(pintype "output")
		)
		(pad "6" smd roundrect
			(at -0.203 1.148 90)
			(size 0.6 0.2)
			(layers "F.Cu" "F.Mask" "F.Paste")
			(roundrect_rratio 0.25)
			(net 658 "/Debug FTDI/LED_TX1")
			(pinfunction "QG")
			(pintype "output")
		)
		(pad "7" smd roundrect
			(at 0.2 1.148 90)
			(size 0.6 0.2)
			(layers "F.Cu" "F.Mask" "F.Paste")
			(roundrect_rratio 0.25)
			(net 659 "/Debug FTDI/LED_RX1")
			(pinfunction "QH")
			(pintype "output")
		)
		(pad "8" smd roundrect
			(at 0.597 1.148 90)
			(size 0.6 0.2)
			(layers "F.Cu" "F.Mask" "F.Paste")
			(roundrect_rratio 0.25)
			(net 1 "GND")
			(pinfunction "GND")
			(pintype "power_in")
		)
		(pad "9" smd roundrect
			(at 1.148 0.597)
			(size 0.6 0.2)
			(layers "F.Cu" "F.Mask" "F.Paste")
			(roundrect_rratio 0.25)
			(net 755 "unconnected-(U9-QH&apos;-Pad9)")
			(pinfunction "QH'")
			(pintype "output+no_connect")
		)
		(pad "10" smd roundrect
			(at 1.148 0.2)
			(size 0.6 0.2)
			(layers "F.Cu" "F.Mask" "F.Paste")
			(roundrect_rratio 0.25)
			(net 6 "/Debug FTDI/FTDI_3V3")
			(pinfunction "~{SRCLR}")
			(pintype "input")
		)
		(pad "11" smd roundrect
			(at 1.148 -0.203)
			(size 0.6 0.2)
			(layers "F.Cu" "F.Mask" "F.Paste")
			(roundrect_rratio 0.25)
			(net 745 "/Debug FTDI/FTDI_EECLK")
			(pinfunction "SRCLK")
			(pintype "input")
		)
		(pad "12" smd roundrect
			(at 1.148 -0.6)
			(size 0.6 0.2)
			(layers "F.Cu" "F.Mask" "F.Paste")
			(roundrect_rratio 0.25)
			(net 738 "/Debug FTDI/FTDI_EECS")
			(pinfunction "RCLK")
			(pintype "input")
		)
		(pad "13" smd roundrect
			(at 0.597 -1.151 90)
			(size 0.6 0.2)
			(layers "F.Cu" "F.Mask" "F.Paste")
			(roundrect_rratio 0.25)
			(net 668 "/Debug FTDI/FTDI_PWREN")
			(pinfunction "~{OE}")
			(pintype "input")
		)
		(pad "14" smd roundrect
			(at 0.2 -1.151 90)
			(size 0.6 0.2)
			(layers "F.Cu" "F.Mask" "F.Paste")
			(roundrect_rratio 0.25)
			(net 744 "/Debug FTDI/FTDI_EEDAT")
			(pinfunction "SER")
			(pintype "input")
		)
		(pad "15" smd roundrect
			(at -0.203 -1.151 90)
			(size 0.6 0.2)
			(layers "F.Cu" "F.Mask" "F.Paste")
			(roundrect_rratio 0.25)
			(net 716 "unconnected-(U9-QA-Pad15)")
			(pinfunction "QA")
			(pintype "output+no_connect")
		)
		(pad "16" smd roundrect
			(at -0.6 -1.151 90)
			(size 0.6 0.2)
			(layers "F.Cu" "F.Mask" "F.Paste")
			(roundrect_rratio 0.25)
			(net 6 "/Debug FTDI/FTDI_3V3")
			(pinfunction "VCC")
			(pintype "power_in")
		)
		(pad "17" smd roundrect
			(at 0 0 90)
			(size 1.2 1.2)
			(layers "F.Cu" "F.Mask" "F.Paste")
			(roundrect_rratio 0.04166666667)
			(net 717 "unconnected-(U9-EP-Pad17)")
			(pinfunction "EP")
			(pintype "no_connect")
		)
	)
)
